# Lightning_PEB_EQL.xlsx — M.2length (si-constraints)
| 15750-1a-165.0714WZS0925.brd |  |  |  |
| Date Wed Oct 26 14:13:27 2016 |  |  |  |
| Net Name | Etch Length (mils) | Manhattan Length (mils) | Percent Manhattan (mils) |
| AGND_P3V3_DEV | 648.25 | 547 | 118.51 |
| D85_PCIE_A_REFCLK_N | 776.54 | 656.3 | 118.32 |
| D85_PCIE_A_REFCLK_P | 775.61 | 605.12 | 128.16999999999999 |
| D85_PCIE_A_RX0_N | 1244.06 | 1050 | 118.48 |
| D85_PCIE_A_RX0_P | 1244.6500000000001 | 1061.81 | 117.22 |
| D85_PCIE_A_RX1_N | 1537.67 | 1435.82 | 107.09 |
| D85_PCIE_A_RX1_P | 1538.32 | 1447.64 | 106.26 |
| D85_PCIE_A_TX0_N | 1053.3499999999999 | 908.27 | 115.97 |
| D85_PCIE_A_TX0_P | 1053.4100000000001 | 896.46 | 117.51 |
| D85_PCIE_A_TX1_N | 1230.52 | 1294.0899999999999 | 95.09 |
| D85_PCIE_A_TX1_P | 1230.57 | 1282.29 | 95.97 |
| D85_PCIE_B_REFCLK_N | 966.59 | 677.37 | 142.69999999999999 |
| D85_PCIE_B_REFCLK_P | 966.45 | 728.55 | 132.65 |
| D85_PCIE_B_RX0_N | 946.63 | 656.29 | 144.24 |
| D85_PCIE_B_RX0_P | 947.24 | 668.11 | 141.78 |
| D85_PCIE_B_RX1_N | 955.34 | 727.16 | 131.38 |
| D85_PCIE_B_RX1_P | 955.96 | 738.97 | 129.36000000000001 |
| D85_PCIE_B_TX0_N | 505.9 | 514.55999999999995 | 98.32 |
| D85_PCIE_B_TX0_P | 505.9 | 502.75 | 100.63 |
| D85_PCIE_B_TX1_N | 536.82000000000005 | 585.42999999999995 | 91.7 |
| D85_PCIE_B_TX1_P | 536.89 | 573.62 | 93.6 |
| P12V | 299.7 | 4399.7299999999996 | 6.81 |
| P1V8_PWR | 4749.3599999999997 | 4467.1400000000003 | 106.32 |
| P1V8_PWR_BIAS | 227.69 | 231.8 | 98.23 |
| P1V8_PWR_EN_R | 189.48 | 169.15 | 112.02 |
| P1V8_PWR_FB | 218.68 | 201.5 | 108.52 |
| P1V8_PWR_GD | 264.47000000000003 | 294.61 | 89.77 |
| P1V8_PWR_SS_C | 144.72 | 126.8 | 114.13 |
| P3V3_DEV_EN | 202.05 | 152.33000000000001 | 132.63999999999999 |
| P3V3_DEV_LL | 373.73 | 570.59 | 65.5 |
| P3V3_DEV_LL_R | 143.29 | 155.11000000000001 | 92.38 |
| P3V3_DEV_MODE | 279.17 | 187.01 | 149.28 |
| P3V3_DEV_PWRGD | 813.12 | 611.27 | 133.02000000000001 |
| P3V3_DEV_RF | 154.56 | 70.5 | 219.23 |
| P3V3_DEV_ROVP | 93.01 | 20.76 | 448.04 |
| P3V3_DEV_SNB | 74.53 | 88 | 84.69 |
| P3V3_DEV_TRIP | 219.11 | 127.33 | 172.08 |
| P3V3_DEV_VBST | 95.9 | 99.2 | 96.68 |
| P3V3_DEV_VBST_RC | 71.64 | 88.11 | 81.31 |
| P3V3_DEV_VDD | 274.63 | 283.2 | 96.97 |
| P3V3_DEV_VFB | 218.13 | 217.53 | 100.28 |
| P3V3_DEV_VFB_R | 121.46 | 124.39 | 97.65 |
| P3V3_DEV_VIN | 0 | 758.68 | 0 |
| P3V3_DEV_VREG | 1303.81 | 744.86 | 175.04 |
| P3V3_DPB | 6425.41 | 5498.94 | 116.85 |
| P3V3_PWR | 2029.29 | 7203.79 | 28.17 |
| SSD_A1_MFG_CLK_TP | 200.35 | 66.650000000000006 | 300.60000000000002 |
| SSD_A1_MFG_DATA_TP | 115.79 | 69.45 | 166.72 |
| SSD_A1_SMB_OE | 131.69999999999999 | 26.65 | 494.2 |
| SSD_B1_MFG_CLK_TP | 200.35 | 66.650000000000006 | 300.60000000000002 |
| SSD_B1_MFG_DATA_TP | 115.79 | 69.45 | 166.72 |
| SSD_B1_SMB_OE | 215.26 | 11.65 | 1847.72 |
| Z50_DEV_RST# | 2047.68 | 1968.72 | 104.01 |
| Z50_SMB_CLK | 4821.53 | 4971.92 | 96.98 |
| Z50_SMB_DATA | 4779.76 | 5046.6099999999997 | 94.71 |
| Z50_SMB_SWITCH_ADDRESS_A0 | 154.05000000000001 | 101.64 | 151.56 |
| Z50_SMB_SWITCH_ADDRESS_A1 | 206.35 | 105.41 | 195.76 |
| Z50_SMB_SWITCH_RESET# | 253.61 | 171.01 | 148.30000000000001 |
| Z50_SSD_A1_ALERT# | 161.47 | 35.06 | 460.56 |
| Z50_SSD_A1_CLKREQ# | 166.99 | 36.32 | 459.78 |
| Z50_SSD_A1_SMB_CLK | 2605.21 | 2545.5700000000002 | 102.34 |
| Z50_SSD_A1_SMB_CLK_LL | 189.93 | 191.95 | 98.95 |
| Z50_SSD_A1_SMB_CLK_LR | 259.52999999999997 | 228.95 | 113.36 |
| Z50_SSD_A1_SMB_CLK_R | 659.83 | 379.59 | 173.83 |
| Z50_SSD_A1_SMB_DATA | 2553.38 | 2575.25 | 99.15 |
| Z50_SSD_A1_SMB_DATA_LL | 209.11 | 243.95 | 85.72 |
| Z50_SSD_A1_SMB_DATA_LR | 129.82 | 96.95 | 133.91 |
| Z50_SSD_A1_SMB_DATA_R | 566.86 | 393.99 | 143.88 |
| Z50_SSD_ACT# | 1049.43 | 1238.6300000000001 | 84.73 |
| Z50_SSD_A_ACT# | 1016.88 | 915 | 111.13 |
| Z50_SSD_A_PRESENT_R# | 150.56 | 86.04 | 174.99 |
| Z50_SSD_A_PRSNT# | 1237.3 | 990 | 124.98 |
| Z50_SSD_A_R_ACT# | 136.83000000000001 | 99.71 | 137.22999999999999 |
| Z50_SSD_B1_ALERT# | 160.80000000000001 | 33.44 | 480.86 |
| Z50_SSD_B1_CLKREQ# | 164.25 | 34.700000000000003 | 473.35 |
| Z50_SSD_B1_SMB_CLK | 3627.73 | 3582.19 | 101.27 |
| Z50_SSD_B1_SMB_CLK_LL | 159.44 | 198.95 | 80.14 |
| Z50_SSD_B1_SMB_CLK_LR | 87 | 73.95 | 117.65 |
| Z50_SSD_B1_SMB_CLK_R | 1000.34 | 655.99 | 152.49 |
| Z50_SSD_B1_SMB_DATA | 3565.05 | 3541.87 | 100.65 |
| Z50_SSD_B1_SMB_DATA_LL | 129.46 | 146.94999999999999 | 88.1 |
| Z50_SSD_B1_SMB_DATA_LR | 110.18 | 123.95 | 88.89 |
| Z50_SSD_B1_SMB_DATA_R | 957.1 | 669.19 | 143.02000000000001 |
| Z50_SSD_B_ACT# | 523.35 | 435 | 120.31 |
| Z50_SSD_B_PRESENT_R# | 149.99 | 124.2 | 120.76 |
| Z50_SSD_B_PRSNT# | 598.05999999999995 | 285 | 209.84 |
| Z50_SSD_B_R_ACT# | 147.53 | 148.09 | 99.62 |
| Z50_SSD_M2_PRSNT# | 1331.39 | 1073.6300000000001 | 124.01 |
| Z50_TEMP_1_A0 | 235.8 | 95.69 | 246.42 |
| Z50_TEMP_1_A1 | 198.9 | 81.290000000000006 | 244.68 |
| Z50_TEMP_1_A2 | 229.64 | 105.09 | 218.52 |
| Z50_TEMP_1_ALERT# | 149.58000000000001 | 121.3 | 123.32 |
| Z50_TEMP_1_CLK | 143.22 | 28.8 | 497.3 |
| Z50_TEMP_1_DATA | 144.19 | 43.2 | 333.77 |
